# T6G (Grand Teton) — schematic netlist excerpt (pin names and nets, part order shuffled) for the footprints in the layout excerpt that follows; sources: Cadence DE-HDL packaged netlist, KiCad conversion of 04192023_DAF0TMB3IC0_F0TG_MB_C_brd_V02_OCP.brd

PC6642_2  Q_CAP  22UF 4V 20% X6S  pkg C0805  page 365 : A = P0V9_CPU1_RT_2D ; B = GND
R6090  Q_RES  4.7K 5% CHIP  pkg 0402LF  page 85 : A = JTAG_SCM_PLD_TCK ; B = GND
R290  Q_RES  1K 1% EMPTY  pkg 0402LF  page 160 : A = PVDD11_S3_P0 ; B = SMB_CPU0_CPU1_APML_BUF2_SDA_R2

(kicad_pcb
	(version 20260206)
	(generator "pcbnew")
	(generator_version "10.0")
	(general
		(thickness 1.6)
		(legacy_teardrops no)
	)
	(paper "A4")
	(title_block
		(title "04192023_DAF0TMB3IC0_F0TG_MB_C_brd_V02_OCP.brd")
		(comment 1 "Grand Teton / footprints 5689-5691 of 8354")
	)
	(layers
		(0 "F.Cu" signal "TOP")
		(4 "In1.Cu" signal "GND")
		(6 "In2.Cu" signal "IN1")
		(8 "In3.Cu" signal "GND1")
		(10 "In4.Cu" signal "IN2")
		(12 "In5.Cu" signal "GND2")
		(14 "In6.Cu" signal "IN3")
		(16 "In7.Cu" signal "GND3")
		(18 "In8.Cu" signal "VCC")
		(20 "In9.Cu" signal "VCC1")
		(22 "In10.Cu" signal "GND4")
		(24 "In11.Cu" signal "IN4")
		(26 "In12.Cu" signal "GND5")
		(28 "In13.Cu" signal "IN5")
		(30 "In14.Cu" signal "GND6")
		(32 "In15.Cu" signal "IN6")
		(34 "In16.Cu" signal "GND7")
		(2 "B.Cu" signal "BOTTOM")
		(9 "F.Adhes" user "F.Adhesive")
		(11 "B.Adhes" user "B.Adhesive")
		(13 "F.Paste" user "Package Geometry/Pastemask Top")
		(15 "B.Paste" user "Package Geometry/Pastemask Bottom")
		(5 "F.SilkS" user "Ref Des/Silkscreen Top")
		(7 "B.SilkS" user "Ref Des/Silkscreen Bottom")
		(1 "F.Mask" user "Board Geometry/Soldermask Top")
		(3 "B.Mask" user "Board Geometry/Soldermask Bottom")
		(17 "Dwgs.User" user "User.Drawings")
		(19 "Cmts.User" user "User.Comments")
		(21 "Eco1.User" user "User.Eco1")
		(23 "Eco2.User" user "User.Eco2")
		(25 "Edge.Cuts" user "Board Geometry/Outline")
		(27 "Margin" user)
		(31 "F.CrtYd" user "Package Geometry/Place Bound Top")
		(29 "B.CrtYd" user "Package Geometry/Place Bound Bottom")
		(35 "F.Fab" user "Ref Des/Assembly Top")
		(33 "B.Fab" user "Ref Des/Assembly Bottom")
	)
	(footprint ""
		(layer "B.Cu")
		(at 17.999456 -383.028698 -90)
		(property "Reference" "PC6642_2"
			(at 0 0 90)
			(layer "B.SilkS")
			(hide yes)
			(effects
				(font
					(size 1.27 1.27)
				)
				(justify mirror)
			)
		)
		(property "Value" ""
			(at 0 0 90)
			(layer "B.Fab")
			(effects
				(font
					(size 1.27 1.27)
				)
				(justify mirror)
			)
		)
		(duplicate_pad_numbers_are_jumpers no)
		(fp_line
			(start -1.524 0.762)
			(end 1.524 0.762)
			(stroke
				(width 0.1524)
				(type default)
			)
			(layer "B.SilkS")
		)
		(fp_line
			(start 1.524 0.762)
			(end 1.524 -0.762)
			(stroke
				(width 0.1524)
				(type default)
			)
			(layer "B.SilkS")
		)
		(fp_line
			(start -1.524 -0.762)
			(end -1.524 0.762)
			(stroke
				(width 0.1524)
				(type default)
			)
			(layer "B.SilkS")
		)
		(fp_line
			(start 1.524 -0.762)
			(end -1.524 -0.762)
			(stroke
				(width 0.1524)
				(type default)
			)
			(layer "B.SilkS")
		)
		(fp_line
			(start -1.1049 0.724916)
			(end -1.1049 -0.724916)
			(stroke
				(width 0.1)
				(type default)
			)
			(layer "B.Fab")
		)
		(fp_line
			(start 1.1049 0.724916)
			(end -1.1049 0.724916)
			(stroke
				(width 0.1)
				(type default)
			)
			(layer "B.Fab")
		)
		(fp_line
			(start -1.1049 -0.724916)
			(end 1.1049 -0.724916)
			(stroke
				(width 0.1)
				(type default)
			)
			(layer "B.Fab")
		)
		(fp_line
			(start 1.1049 -0.724916)
			(end 1.1049 0.724916)
			(stroke
				(width 0.1)
				(type default)
			)
			(layer "B.Fab")
		)
		(pad "1" smd rect
			(at 0.889 0 270)
			(size 1.016 1.27)
			(layers "B.Cu" "B.Mask" "B.Paste")
			(net "P0V9_CPU1_RT_2D")
		)
		(pad "2" smd rect
			(at -0.889 0 270)
			(size 1.016 1.27)
			(layers "B.Cu" "B.Mask" "B.Paste")
			(net "GND")
		)
	)
	(footprint ""
		(layer "B.Cu")
		(at 229.616 -216.662 180)
		(property "Reference" "R290"
			(at 0 0 0)
			(layer "B.SilkS")
			(hide yes)
			(effects
				(font
					(size 1.27 1.27)
				)
				(justify mirror)
			)
		)
		(property "Value" ""
			(at 0 0 0)
			(layer "B.Fab")
			(effects
				(font
					(size 1.27 1.27)
				)
				(justify mirror)
			)
		)
		(duplicate_pad_numbers_are_jumpers no)
		(fp_line
			(start 0.7874 0.4064)
			(end 0.7874 -0.4064)
			(stroke
				(width 0.1524)
				(type default)
			)
			(layer "B.SilkS")
		)
		(fp_line
			(start 0.7874 -0.4064)
			(end -0.7874 -0.4064)
			(stroke
				(width 0.1524)
				(type default)
			)
			(layer "B.SilkS")
		)
		(fp_line
			(start -0.7874 0.4064)
			(end 0.7874 0.4064)
			(stroke
				(width 0.1524)
				(type default)
			)
			(layer "B.SilkS")
		)
		(fp_line
			(start -0.7874 -0.4064)
			(end -0.7874 0.4064)
			(stroke
				(width 0.1524)
				(type default)
			)
			(layer "B.SilkS")
		)
		(fp_line
			(start 0.67945 0.3048)
			(end 0.67945 -0.305054)
			(stroke
				(width 0.1)
				(type default)
			)
			(layer "B.Fab")
		)
		(fp_line
			(start 0.67945 -0.305054)
			(end 0.12065 -0.305054)
			(stroke
				(width 0.1)
				(type default)
			)
			(layer "B.Fab")
		)
		(fp_line
			(start 0.12065 0.3048)
			(end 0.67945 0.3048)
			(stroke
				(width 0.1)
				(type default)
			)
			(layer "B.Fab")
		)
		(fp_line
			(start 0.12065 0.2794)
			(end 0.12065 0.3048)
			(stroke
				(width 0.1)
				(type default)
			)
			(layer "B.Fab")
		)
		(fp_line
			(start 0.12065 -0.2794)
			(end -0.12065 -0.2794)
			(stroke
				(width 0.1)
				(type default)
			)
			(layer "B.Fab")
		)
		(fp_line
			(start 0.12065 -0.305054)
			(end 0.12065 -0.2794)
			(stroke
				(width 0.1)
				(type default)
			)
			(layer "B.Fab")
		)
		(fp_line
			(start -0.120396 0.3048)
			(end -0.120396 0.2794)
			(stroke
				(width 0.1)
				(type default)
			)
			(layer "B.Fab")
		)
		(fp_line
			(start -0.120396 0.2794)
			(end 0.12065 0.2794)
			(stroke
				(width 0.1)
				(type default)
			)
			(layer "B.Fab")
		)
		(fp_line
			(start -0.12065 -0.2794)
			(end -0.12065 -0.3048)
			(stroke
				(width 0.1)
				(type default)
			)
			(layer "B.Fab")
		)
		(fp_line
			(start -0.12065 -0.3048)
			(end -0.67945 -0.3048)
			(stroke
				(width 0.1)
				(type default)
			)
			(layer "B.Fab")
		)
		(fp_line
			(start -0.67945 0.3048)
			(end -0.120396 0.3048)
			(stroke
				(width 0.1)
				(type default)
			)
			(layer "B.Fab")
		)
		(fp_line
			(start -0.67945 -0.3048)
			(end -0.67945 0.3048)
			(stroke
				(width 0.1)
				(type default)
			)
			(layer "B.Fab")
		)
		(pad "1" smd circle
			(at 0.40005 0)
			(size 0 0)
			(layers "B.Cu" "B.Mask" "B.Paste")
			(net "PVDD11_S3_P0")
		)
		(pad "2" smd circle
			(at -0.40005 0)
			(size 0 0)
			(layers "B.Cu" "B.Mask" "B.Paste")
			(net "SMB_CPU0_CPU1_APML_BUF2_SDA_R2")
		)
	)
	(footprint ""
		(layer "B.Cu")
		(at 137.928604 -64.036702 -90)
		(property "Reference" "R6090"
			(at 0 0 90)
			(layer "B.SilkS")
			(hide yes)
			(effects
				(font
					(size 1.27 1.27)
				)
				(justify mirror)
			)
		)
		(property "Value" ""
			(at 0 0 90)
			(layer "B.Fab")
			(effects
				(font
					(size 1.27 1.27)
				)
				(justify mirror)
			)
		)
		(duplicate_pad_numbers_are_jumpers no)
		(fp_line
			(start -0.7874 0.4064)
			(end 0.7874 0.4064)
			(stroke
				(width 0.1524)
				(type default)
			)
			(layer "B.SilkS")
		)
		(fp_line
			(start 0.7874 0.4064)
			(end 0.7874 -0.4064)
			(stroke
				(width 0.1524)
				(type default)
			)
			(layer "B.SilkS")
		)
		(fp_line
			(start -0.7874 -0.4064)
			(end -0.7874 0.4064)
			(stroke
				(width 0.1524)
				(type default)
			)
			(layer "B.SilkS")
		)
		(fp_line
			(start 0.7874 -0.4064)
			(end -0.7874 -0.4064)
			(stroke
				(width 0.1524)
				(type default)
			)
			(layer "B.SilkS")
		)
		(fp_line
			(start -0.67945 0.3048)
			(end -0.120396 0.3048)
			(stroke
				(width 0.1)
				(type default)
			)
			(layer "B.Fab")
		)
		(fp_line
			(start -0.120396 0.3048)
			(end -0.120396 0.2794)
			(stroke
				(width 0.1)
				(type default)
			)
			(layer "B.Fab")
		)
		(fp_line
			(start 0.12065 0.3048)
			(end 0.67945 0.3048)
			(stroke
				(width 0.1)
				(type default)
			)
			(layer "B.Fab")
		)
		(fp_line
			(start 0.67945 0.3048)
			(end 0.67945 -0.305054)
			(stroke
				(width 0.1)
				(type default)
			)
			(layer "B.Fab")
		)
		(fp_line
			(start -0.120396 0.2794)
			(end 0.12065 0.2794)
			(stroke
				(width 0.1)
				(type default)
			)
			(layer "B.Fab")
		)
		(fp_line
			(start 0.12065 0.2794)
			(end 0.12065 0.3048)
			(stroke
				(width 0.1)
				(type default)
			)
			(layer "B.Fab")
		)
		(fp_line
			(start -0.12065 -0.2794)
			(end -0.12065 -0.3048)
			(stroke
				(width 0.1)
				(type default)
			)
			(layer "B.Fab")
		)
		(fp_line
			(start 0.12065 -0.2794)
			(end -0.12065 -0.2794)
			(stroke
				(width 0.1)
				(type default)
			)
			(layer "B.Fab")
		)
		(fp_line
			(start -0.67945 -0.3048)
			(end -0.67945 0.3048)
			(stroke
				(width 0.1)
				(type default)
			)
			(layer "B.Fab")
		)
		(fp_line
			(start -0.12065 -0.3048)
			(end -0.67945 -0.3048)
			(stroke
				(width 0.1)
				(type default)
			)
			(layer "B.Fab")
		)
		(fp_line
			(start 0.12065 -0.305054)
			(end 0.12065 -0.2794)
			(stroke
				(width 0.1)
				(type default)
			)
			(layer "B.Fab")
		)
		(fp_line
			(start 0.67945 -0.305054)
			(end 0.12065 -0.305054)
			(stroke
				(width 0.1)
				(type default)
			)
			(layer "B.Fab")
		)
		(pad "1" smd circle
			(at 0.40005 0 90)
			(size 0 0)
			(layers "B.Cu" "B.Mask" "B.Paste")
			(net "JTAG_SCM_PLD_TCK")
		)
		(pad "2" smd circle
			(at -0.40005 0 90)
			(size 0 0)
			(layers "B.Cu" "B.Mask" "B.Paste")
			(net "GND")
		)
	)
)
